#ISCELL
  logical_power cad_note *
  *
#ISCELL
  mstr_misc dns *
  *
#ISCELL
  pure_quanta quanta_title_block_c *
  *
#ISCELL
  logical_power universal_gnd *
  page153_i1
#ISCELL
  logical_power gnd *
  page153_i10
#ISCELL
  standard offpage *
  page153_i100
#CELL
  pure_quanta q_cap *
  page153_i101
#CELL
  pure_quanta q_res *
  page153_i102
#CELL
  pure_quanta q_res *
  page153_i103
#CELL
  pure_quanta schottky_ac *
  page153_i104
#CELL
  pure_quanta q_res *
  page153_i105
#ISCELL
  logical_power gnd *
  page153_i106
#CELL
  pure_quanta q_cap *
  page153_i107
#CELL
  pure_quanta q_res *
  page153_i108
#ISCELL
  logical_power vccaux15 *
  page153_i109
#ISCELL
  standard offpage *
  page153_i11
#CELL
  pure_quanta q_res *
  page153_i110
#CELL
  pure_quanta q_cap *
  page153_i111
#ISCELL
  logical_power gnd *
  page153_i112
#CELL
  pure_quanta q_cap *
  page153_i113
#ISCELL
  logical_power universal_power *
  page153_i114
#ISCELL
  standard offpage *
  page153_i115
#ISCELL
  standard offpage *
  page153_i12
#CELL
  pure_quanta q_res *
  page153_i13
#ISCELL
  logical_power universal_power *
  page153_i14
#CELL
  pure_quanta q_res *
  page153_i15
#ISCELL
  logical_power universal_power *
  page153_i16
#CELL
  pure_quanta mosfet_nch_dual *
  page153_i17
#ISCELL
  logical_power gnd *
  page153_i18
#CELL
  pure_quanta q_res *
  page153_i19
#ISCELL
  logical_power universal_gnd *
  page153_i2
#CELL
  pure_quanta q_res *
  page153_i20
#CELL
  pure_quanta mosfet_nch_dual *
  page153_i21
#CELL
  pure_quanta q_res *
  page153_i22
#CELL
  pure_quanta 74lvc2g07dw7 *
  page153_i23
#ISCELL
  logical_power universal_gnd *
  page153_i24
#CELL
  pure_quanta q_res *
  page153_i25
#CELL
  pure_quanta 74lvc2g07dw7 *
  page153_i26
#CELL
  pure_quanta q_cap *
  page153_i27
#ISCELL
  logical_power universal_power *
  page153_i28
#ISCELL
  logical_power universal_gnd *
  page153_i29
#ISCELL
  standard offpage *
  page153_i3
#CELL
  pure_quanta q_cap *
  page153_i30
#ISCELL
  logical_power universal_power *
  page153_i31
#ISCELL
  logical_power gnd *
  page153_i32
#CELL
  pure_quanta q_res *
  page153_i33
#ISCELL
  logical_power gnd *
  page153_i34
#ISCELL
  logical_power gnd *
  page153_i35
#CELL
  pure_quanta mosfet_nch_dual *
  page153_i36
#ISCELL
  logical_power gnd *
  page153_i37
#CELL
  pure_quanta diode_tvs *
  page153_i38
#CELL
  pure_quanta q_res *
  page153_i39
#CELL
  pure_quanta q_res *
  page153_i4
#ISCELL
  logical_power gnd *
  page153_i40
#CELL
  pure_quanta q_res *
  page153_i41
#CELL
  pure_quanta q_res *
  page153_i42
#ISCELL
  logical_power universal_power *
  page153_i43
#CELL
  pure_quanta q_cap *
  page153_i44
#CELL
  pure_quanta q_res *
  page153_i45
#CELL
  pure_quanta q_res *
  page153_i46
#CELL
  pure_quanta q_res *
  page153_i47
#ISCELL
  logical_power gnd *
  page153_i48
#CELL
  pure_quanta q_res *
  page153_i49
#ISCELL
  standard offpage *
  page153_i5
#CELL
  pure_quanta q_res *
  page153_i50
#CELL
  pure_quanta max15090bewit *
  page153_i51
#ISCELL
  logical_power universal_power *
  page153_i52
#ISCELL
  logical_power gnd *
  page153_i53
#CELL
  pure_quanta q_cap *
  page153_i54
#CELL
  pure_quanta q_cap *
  page153_i55
#CELL
  pure_quanta q_res *
  page153_i56
#ISCELL
  logical_power gnd *
  page153_i57
#CELL
  pure_quanta q_res *
  page153_i58
#ISCELL
  logical_power gnd *
  page153_i59
#ISCELL
  standard offpage *
  page153_i6
#CELL
  pure_quanta q_res *
  page153_i60
#CELL
  pure_quanta max15090bewit *
  page153_i61
#CELL
  pure_quanta q_res *
  page153_i62
#ISCELL
  logical_power universal_power *
  page153_i63
#CELL
  pure_quanta q_res *
  page153_i64
#ISCELL
  logical_power gnd *
  page153_i65
#CELL
  pure_quanta q_cap *
  page153_i66
#ISCELL
  logical_power universal_power *
  page153_i67
#CELL
  pure_quanta q_res *
  page153_i68
#ISCELL
  logical_power gnd *
  page153_i69
#CELL
  pure_quanta q_res *
  page153_i7
#CELL
  pure_quanta q_res *
  page153_i70
#CELL
  pure_quanta q_cap *
  page153_i71
#CELL
  pure_quanta q_cap *
  page153_i72
#CELL
  pure_quanta q_res *
  page153_i73
#CELL
  pure_quanta q_res *
  page153_i74
#ISCELL
  standard offpage *
  page153_i75
#CELL
  pure_quanta q_res *
  page153_i76
#ISCELL
  standard offpage *
  page153_i77
#ISCELL
  standard offpage *
  page153_i78
#ISCELL
  logical_power gnd *
  page153_i79
#ISCELL
  logical_power universal_power *
  page153_i8
#CELL
  pure_quanta q_res *
  page153_i80
#CELL
  pure_quanta q_cap *
  page153_i81
#CELL
  pure_quanta q_res *
  page153_i82
#CELL
  pure_quanta q_cap *
  page153_i83
#CELL
  pure_quanta q_res *
  page153_i84
#ISCELL
  logical_power gnd *
  page153_i85
#CELL
  pure_quanta schottky_ac *
  page153_i86
#CELL
  pure_quanta q_res *
  page153_i87
#CELL
  pure_quanta q_res *
  page153_i88
#ISCELL
  logical_power gnd *
  page153_i89
#CELL
  pure_quanta mosfet_nch_dual *
  page153_i9
#CELL
  pure_quanta q_res *
  page153_i90
#ISCELL
  logical_power vccaux15 *
  page153_i91
#CELL
  pure_quanta q_res *
  page153_i92
#CELL
  pure_quanta q_cap *
  page153_i93
#CELL
  pure_quanta q_cap *
  page153_i94
#ISCELL
  logical_power gnd *
  page153_i95
#CELL
  pure_quanta q_cap *
  page153_i96
#ISCELL
  logical_power universal_power *
  page153_i97
#ISCELL
  standard offpage *
  page153_i98
#ISCELL
  standard offpage *
  page153_i99
